# T6G (Grand Teton) — schematic netlist excerpt (pin names and nets, part order shuffled) for the footprints in the layout excerpt that follows; sources: Cadence DE-HDL packaged netlist, KiCad conversion of 04192023_DAF0TMB3IC0_F0TG_MB_C_brd_V02_OCP.brd

H115  GND_HOLE  EMPTY  pkg TH  page 230
  GND2  = GND
  GND3  = GND
  GND4  = GND
  GND5  = GND
  GND6  = GND
  GND7  = GND
  GND8  = GND
  GND9  = GND

(kicad_pcb
	(version 20260206)
	(generator "pcbnew")
	(generator_version "10.0")
	(general
		(thickness 1.6)
		(legacy_teardrops no)
	)
	(paper "A4")
	(title_block
		(title "04192023_DAF0TMB3IC0_F0TG_MB_C_brd_V02_OCP.brd")
		(comment 1 "Grand Teton / footprints 3641-3641 of 8354")
	)
	(layers
		(0 "F.Cu" signal "TOP")
		(4 "In1.Cu" signal "GND")
		(6 "In2.Cu" signal "IN1")
		(8 "In3.Cu" signal "GND1")
		(10 "In4.Cu" signal "IN2")
		(12 "In5.Cu" signal "GND2")
		(14 "In6.Cu" signal "IN3")
		(16 "In7.Cu" signal "GND3")
		(18 "In8.Cu" signal "VCC")
		(20 "In9.Cu" signal "VCC1")
		(22 "In10.Cu" signal "GND4")
		(24 "In11.Cu" signal "IN4")
		(26 "In12.Cu" signal "GND5")
		(28 "In13.Cu" signal "IN5")
		(30 "In14.Cu" signal "GND6")
		(32 "In15.Cu" signal "IN6")
		(34 "In16.Cu" signal "GND7")
		(2 "B.Cu" signal "BOTTOM")
		(9 "F.Adhes" user "F.Adhesive")
		(11 "B.Adhes" user "B.Adhesive")
		(13 "F.Paste" user "Package Geometry/Pastemask Top")
		(15 "B.Paste" user "Package Geometry/Pastemask Bottom")
		(5 "F.SilkS" user "Ref Des/Silkscreen Top")
		(7 "B.SilkS" user "Ref Des/Silkscreen Bottom")
		(1 "F.Mask" user "Board Geometry/Soldermask Top")
		(3 "B.Mask" user "Board Geometry/Soldermask Bottom")
		(17 "Dwgs.User" user "User.Drawings")
		(19 "Cmts.User" user "User.Comments")
		(21 "Eco1.User" user "User.Eco1")
		(23 "Eco2.User" user "User.Eco2")
		(25 "Edge.Cuts" user "Board Geometry/Outline")
		(27 "Margin" user)
		(31 "F.CrtYd" user "Package Geometry/Place Bound Top")
		(29 "B.CrtYd" user "Package Geometry/Place Bound Bottom")
		(35 "F.Fab" user "Ref Des/Assembly Top")
		(33 "B.Fab" user "Ref Des/Assembly Bottom")
	)
	(footprint ""
		(layer "F.Cu")
		(at 235.89996 -81.700116 180)
		(property "Reference" "H115"
			(at -4.5466 -7.559548 180)
			(unlocked yes)
			(layer "B.SilkS")
			(effects
				(font
					(size 0.7874 0.5842)
					(thickness 0.1524)
				)
				(justify left mirror)
			)
		)
		(property "Value" ""
			(at 0 0 180)
			(layer "F.Fab")
			(effects
				(font
					(size 1.27 1.27)
				)
			)
		)
		(duplicate_pad_numbers_are_jumpers no)
		(fp_circle
			(center 0 0)
			(end -7.999984 0)
			(stroke
				(width 0.1524)
				(type default)
			)
			(fill no)
			(layer "F.SilkS")
		)
		(fp_circle
			(center 0 0)
			(end -7.999984 0)
			(stroke
				(width 0.1524)
				(type default)
			)
			(fill no)
			(layer "B.SilkS")
		)
		(fp_circle
			(center 0 0)
			(end -7.999984 0)
			(stroke
				(width 0.1)
				(type default)
			)
			(fill no)
			(layer "B.Fab")
		)
		(fp_circle
			(center 0 0)
			(end -7.999984 0)
			(stroke
				(width 0.1)
				(type default)
			)
			(fill no)
			(layer "F.Fab")
		)
		(pad "" np_thru_hole oval
			(at 0 0 90)
			(size 5.08 6.477)
			(drill oval 5.08 6.477)
			(layers "*.Cu" "*.Mask")
			(clearance 0.381)
			(thermal_gap 0.381)
		)
		(pad "2" thru_hole circle
			(at 4.38023 0 180)
			(size 0.9144 0.9144)
			(drill 0.5588)
			(layers "*.Cu" "*.Mask")
			(remove_unused_layers no)
			(net "GND")
			(clearance 0.0762)
			(thermal_gap 0.0762)
		)
		(pad "3" thru_hole circle
			(at 3.097276 -3.097276 180)
			(size 0.9144 0.9144)
			(drill 0.5588)
			(layers "*.Cu" "*.Mask")
			(remove_unused_layers no)
			(net "GND")
			(clearance 0.0762)
			(thermal_gap 0.0762)
		)
		(pad "4" thru_hole circle
			(at 0 -4.38023 180)
			(size 0.9144 0.9144)
			(drill 0.5588)
			(layers "*.Cu" "*.Mask")
			(remove_unused_layers no)
			(net "GND")
			(clearance 0.0762)
			(thermal_gap 0.0762)
		)
		(pad "5" thru_hole circle
			(at -3.097276 -3.097276 180)
			(size 0.9144 0.9144)
			(drill 0.5588)
			(layers "*.Cu" "*.Mask")
			(remove_unused_layers no)
			(net "GND")
			(clearance 0.0762)
			(thermal_gap 0.0762)
		)
		(pad "6" thru_hole circle
			(at -4.38023 0 180)
			(size 0.9144 0.9144)
			(drill 0.5588)
			(layers "*.Cu" "*.Mask")
			(remove_unused_layers no)
			(net "GND")
			(clearance 0.0762)
			(thermal_gap 0.0762)
		)
		(pad "7" thru_hole circle
			(at -3.097276 3.097276 180)
			(size 0.9144 0.9144)
			(drill 0.5588)
			(layers "*.Cu" "*.Mask")
			(remove_unused_layers no)
			(net "GND")
			(clearance 0.0762)
			(thermal_gap 0.0762)
		)
		(pad "8" thru_hole circle
			(at 0 4.38023 180)
			(size 0.9144 0.9144)
			(drill 0.5588)
			(layers "*.Cu" "*.Mask")
			(remove_unused_layers no)
			(net "GND")
			(clearance 0.0762)
			(thermal_gap 0.0762)
		)
		(pad "9" thru_hole circle
			(at 3.097276 3.097276 180)
			(size 0.9144 0.9144)
			(drill 0.5588)
			(layers "*.Cu" "*.Mask")
			(remove_unused_layers no)
			(net "GND")
			(clearance 0.0762)
			(thermal_gap 0.0762)
		)
		(zone
			(layer "F.Cu")
			(hatch none 0.5)
			(connect_pads
				(clearance 0)
			)
			(min_thickness 0.25)
			(keepout
				(tracks not_allowed)
				(vias allowed)
				(pads allowed)
				(copperpour not_allowed)
				(footprints allowed)
			)
			(placement
				(enabled no)
				(sheetname "")
			)
			(fill
				(thermal_gap 0.5)
				(thermal_bridge_width 0.5)
				(island_removal_mode 0)
			)
			(polygon
				(pts
					(arc
						(start 230.39197 -81.700116)
						(mid 232.005223 -85.594853)
						(end 235.89996 -87.208106)
					)
					(arc
						(start 235.89996 -86.725506)
						(mid 230.87457 -81.700116)
						(end 235.89996 -76.674726)
					)
					(arc
						(start 235.89996 -76.192126)
						(mid 232.005223 -77.805379)
						(end 230.39197 -81.700116)
					)
				)
			)
		)
		(zone
			(layer "F.Cu")
			(hatch none 0.5)
			(connect_pads
				(clearance 0)
			)
			(min_thickness 0.25)
			(keepout
				(tracks not_allowed)
				(vias allowed)
				(pads allowed)
				(copperpour not_allowed)
				(footprints allowed)
			)
			(placement
				(enabled no)
				(sheetname "")
			)
			(fill
				(thermal_gap 0.5)
				(thermal_bridge_width 0.5)
				(island_removal_mode 0)
			)
			(polygon
				(pts
					(arc
						(start 241.40795 -81.700116)
						(mid 239.794697 -85.594853)
						(end 235.89996 -87.208106)
					)
					(arc
						(start 235.89996 -86.725506)
						(mid 240.92535 -81.700116)
						(end 235.89996 -76.674726)
					)
					(arc
						(start 235.89996 -76.192126)
						(mid 239.794697 -77.805379)
						(end 241.40795 -81.700116)
					)
				)
			)
		)
		(zone
			(layers "F.Cu" "B.Cu" "In1.Cu" "In2.Cu" "In3.Cu" "In4.Cu" "In5.Cu" "In6.Cu"
				"In7.Cu" "In8.Cu" "In9.Cu" "In10.Cu" "In11.Cu" "In12.Cu" "In13.Cu" "In14.Cu"
				"In15.Cu" "In16.Cu"
			)
			(hatch none 0.5)
			(connect_pads
				(clearance 0)
			)
			(min_thickness 0.25)
			(keepout
				(tracks not_allowed)
				(vias allowed)
				(pads allowed)
				(copperpour not_allowed)
				(footprints allowed)
			)
			(placement
				(enabled no)
				(sheetname "")
			)
			(fill
				(thermal_gap 0.5)
				(thermal_bridge_width 0.5)
				(island_removal_mode 0)
			)
			(polygon
				(pts
					(arc
						(start 233.71556 -78.64221)
						(mid 235.89996 -85.458093)
						(end 238.08436 -78.64221)
					)
				)
			)
		)
		(zone
			(layer "B.Cu")
			(hatch none 0.5)
			(connect_pads
				(clearance 0)
			)
			(min_thickness 0.25)
			(keepout
				(tracks not_allowed)
				(vias allowed)
				(pads allowed)
				(copperpour not_allowed)
				(footprints allowed)
			)
			(placement
				(enabled no)
				(sheetname "")
			)
			(fill
				(thermal_gap 0.5)
				(thermal_bridge_width 0.5)
				(island_removal_mode 0)
			)
			(polygon
				(pts
					(arc
						(start 235.89996 -89.7001)
						(mid 227.899976 -81.700116)
						(end 235.89996 -73.700132)
					)
					(arc
						(start 235.89996 -76.446126)
						(mid 232.184828 -77.984984)
						(end 230.64597 -81.700116)
					)
					(arc
						(start 230.64597 -81.700116)
						(mid 232.184828 -85.415248)
						(end 235.89996 -86.954106)
					)
				)
			)
		)
		(zone
			(layer "B.Cu")
			(hatch none 0.5)
			(connect_pads
				(clearance 0)
			)
			(min_thickness 0.25)
			(keepout
				(tracks not_allowed)
				(vias allowed)
				(pads allowed)
				(copperpour not_allowed)
				(footprints allowed)
			)
			(placement
				(enabled no)
				(sheetname "")
			)
			(fill
				(thermal_gap 0.5)
				(thermal_bridge_width 0.5)
				(island_removal_mode 0)
			)
			(polygon
				(pts
					(arc
						(start 235.89996 -89.7001)
						(mid 243.899944 -81.700116)
						(end 235.89996 -73.700132)
					)
					(arc
						(start 235.89996 -76.446126)
						(mid 239.615092 -77.984984)
						(end 241.15395 -81.700116)
					)
					(arc
						(start 241.15395 -81.700116)
						(mid 239.615092 -85.415248)
						(end 235.89996 -86.954106)
					)
				)
			)
		)
	)
)
